# S9S_MB_2U (Grand Teton) — schematic netlist excerpt (pin names and nets, part order shuffled) for the footprints in the layout excerpt that follows; sources: Cadence DE-HDL packaged netlist, KiCad conversion of 03242023_DA0F0TMBIJ0_F0T_Motherboard_J_brd_V01_OCP.brd

U247  9FGL0251DKILFT  IC  pkg VFQFPN24_TH_0-5_4X4XI  page 212
  \xin||clkin_25\  = CLK_GEN2_XTAL_IN
  X2  = CLK_GEN2_XTAL_OUT
  \vddxtal3.3\  = VFG3P3_CLK_GEN
  \vsadr||ref3.3\  = CLK_GEN2_SMB_SADR
  GNDREF  = GND
  GNDDIG  = GND
  \vdddig3.3\  = VFG3P3_CLK_GEN
  \sclk_3.3\  = SMB_HOST_CLK_GEN2_3V3AUX_SCL
  \sdata_3.3\  = SMB_HOST_CLK_GEN2_3V3AUX_SDA
  GND_10  = GND
  \vdd3.3_11\  = VFG3P3_CLK_GEN
  \voe0#\  = CLK_GEN2_BMC_RC_OE_R3_N
  DIF0  = CLK_100M_BMC_RC_DP_R
  \dif0#\  = CLK_100M_BMC_RC_DN_R
  GNDA  = GND
  \vdda3.3\  = VFG_3P3A_CLK_GEN
  DIF1  = CLK_100M_GPU_FPGA_DP_R
  \dif1#\  = CLK_100M_GPU_FPGA_DN_R
  \voe1#\  = CLK_GEN2_GPU_OE_N
  \vdd3.3_20\  = VFG3P3_CLK_GEN
  GND_21  = GND
  \^ckpwrgd_pd#\  = P3V3_PWRGD_CLKGEN
  \^vss_en_tri\  = FG_SS_EN
  GNDXTAL  = GND
  TH_GND  = GND

(kicad_pcb
	(version 20260206)
	(generator "pcbnew")
	(generator_version "10.0")
	(general
		(thickness 1.6)
		(legacy_teardrops no)
	)
	(paper "A4")
	(title_block
		(title "03242023_DA0F0TMBIJ0_F0T_Motherboard_J_brd_V01_OCP.brd")
		(comment 1 "Grand Teton / footprints 2505-2505 of 6105")
	)
	(layers
		(0 "F.Cu" signal "TOP")
		(4 "In1.Cu" signal "GND")
		(6 "In2.Cu" signal "IN1")
		(8 "In3.Cu" signal "GND1")
		(10 "In4.Cu" signal "IN2")
		(12 "In5.Cu" signal "GND2")
		(14 "In6.Cu" signal "IN3")
		(16 "In7.Cu" signal "GND3")
		(18 "In8.Cu" signal "VCC")
		(20 "In9.Cu" signal "VCC1")
		(22 "In10.Cu" signal "GND4")
		(24 "In11.Cu" signal "IN4")
		(26 "In12.Cu" signal "GND5")
		(28 "In13.Cu" signal "IN5")
		(30 "In14.Cu" signal "GND6")
		(32 "In15.Cu" signal "IN6")
		(34 "In16.Cu" signal "GND7")
		(2 "B.Cu" signal "BOTTOM")
		(9 "F.Adhes" user "F.Adhesive")
		(11 "B.Adhes" user "B.Adhesive")
		(13 "F.Paste" user "Package Geometry/Pastemask Top")
		(15 "B.Paste" user "Package Geometry/Pastemask Bottom")
		(5 "F.SilkS" user "Ref Des/Silkscreen Top")
		(7 "B.SilkS" user "Ref Des/Silkscreen Bottom")
		(1 "F.Mask" user "Board Geometry/Soldermask Top")
		(3 "B.Mask" user "Board Geometry/Soldermask Bottom")
		(17 "Dwgs.User" user "User.Drawings")
		(19 "Cmts.User" user "User.Comments")
		(21 "Eco1.User" user "User.Eco1")
		(23 "Eco2.User" user "User.Eco2")
		(25 "Edge.Cuts" user "Board Geometry/Outline")
		(27 "Margin" user)
		(31 "F.CrtYd" user "Package Geometry/Place Bound Top")
		(29 "B.CrtYd" user "Package Geometry/Place Bound Bottom")
		(35 "F.Fab" user "Ref Des/Assembly Top")
		(33 "B.Fab" user "Ref Des/Assembly Bottom")
	)
	(footprint ""
		(layer "F.Cu")
		(at 235.404406 -250.630436 180)
		(property "Reference" "U247"
			(at -2.7432 -3.012948 180)
			(unlocked yes)
			(layer "F.SilkS")
			(effects
				(font
					(size 0.7874 0.5842)
					(thickness 0.1524)
				)
				(justify left)
			)
		)
		(property "Value" ""
			(at 0 0 180)
			(layer "F.Fab")
			(effects
				(font
					(size 1.27 1.27)
				)
			)
		)
		(duplicate_pad_numbers_are_jumpers no)
		(fp_line
			(start 2.050034 2.050034)
			(end 2.050034 1.516634)
			(stroke
				(width 0.1524)
				(type default)
			)
			(layer "F.SilkS")
		)
		(fp_line
			(start 2.050034 -1.516634)
			(end 2.050034 -2.050034)
			(stroke
				(width 0.1524)
				(type default)
			)
			(layer "F.SilkS")
		)
		(fp_line
			(start 2.050034 -2.050034)
			(end 1.516634 -2.050034)
			(stroke
				(width 0.1524)
				(type default)
			)
			(layer "F.SilkS")
		)
		(fp_line
			(start 1.516634 2.050034)
			(end 2.050034 2.050034)
			(stroke
				(width 0.1524)
				(type default)
			)
			(layer "F.SilkS")
		)
		(fp_line
			(start -1.516634 -2.050034)
			(end -2.050034 -2.050034)
			(stroke
				(width 0.1524)
				(type default)
			)
			(layer "F.SilkS")
		)
		(fp_line
			(start -2.050034 2.050034)
			(end -1.516634 2.050034)
			(stroke
				(width 0.1524)
				(type default)
			)
			(layer "F.SilkS")
		)
		(fp_line
			(start -2.050034 1.516634)
			(end -2.050034 2.050034)
			(stroke
				(width 0.1524)
				(type default)
			)
			(layer "F.SilkS")
		)
		(fp_line
			(start -2.050034 -2.050034)
			(end -2.050034 -1.516634)
			(stroke
				(width 0.1524)
				(type default)
			)
			(layer "F.SilkS")
		)
		(fp_poly
			(pts
				(xy -2.634234 -1.542034) (xy -2.050034 -1.542034) (xy -2.050034 -2.126234) (xy -2.634234 -2.126234)
			)
			(stroke
				(width 0)
				(type default)
			)
			(fill yes)
			(layer "F.SilkS")
		)
		(fp_line
			(start 2.050034 2.050034)
			(end 2.050034 -2.050034)
			(stroke
				(width 0.1)
				(type default)
			)
			(layer "F.Fab")
		)
		(fp_line
			(start 2.050034 -2.050034)
			(end -2.050034 -2.050034)
			(stroke
				(width 0.1)
				(type default)
			)
			(layer "F.Fab")
		)
		(fp_line
			(start -2.050034 2.050034)
			(end 2.050034 2.050034)
			(stroke
				(width 0.1)
				(type default)
			)
			(layer "F.Fab")
		)
		(fp_line
			(start -2.050034 -2.050034)
			(end -2.050034 2.050034)
			(stroke
				(width 0.1)
				(type default)
			)
			(layer "F.Fab")
		)
		(fp_poly
			(pts
				(xy -2.634234 -1.542034) (xy -2.050034 -1.542034) (xy -2.050034 -2.126234) (xy -2.634234 -2.126234)
			)
			(stroke
				(width 0)
				(type default)
			)
			(fill yes)
			(layer "F.Fab")
		)
		(pad "1" smd rect
			(at -1.875028 -1.249934 90)
			(size 0.254 0.5588)
			(layers "F.Cu" "F.Mask" "F.Paste")
			(net "CLK_GEN2_XTAL_IN")
		)
		(pad "2" smd rect
			(at -1.875028 -0.750062 90)
			(size 0.254 0.5588)
			(layers "F.Cu" "F.Mask" "F.Paste")
			(net "CLK_GEN2_XTAL_OUT")
		)
		(pad "3" smd rect
			(at -1.875028 -0.249936 90)
			(size 0.254 0.5588)
			(layers "F.Cu" "F.Mask" "F.Paste")
			(net "VFG3P3_CLK_GEN")
		)
		(pad "4" smd rect
			(at -1.875028 0.249936 90)
			(size 0.254 0.5588)
			(layers "F.Cu" "F.Mask" "F.Paste")
			(net "CLK_GEN2_SMB_SADR")
		)
		(pad "5" smd rect
			(at -1.875028 0.750062 90)
			(size 0.254 0.5588)
			(layers "F.Cu" "F.Mask" "F.Paste")
			(net "GND")
		)
		(pad "6" smd rect
			(at -1.875028 1.249934 90)
			(size 0.254 0.5588)
			(layers "F.Cu" "F.Mask" "F.Paste")
			(net "GND")
		)
		(pad "7" smd rect
			(at -1.249934 1.875028 180)
			(size 0.254 0.5588)
			(layers "F.Cu" "F.Mask" "F.Paste")
			(net "VFG3P3_CLK_GEN")
		)
		(pad "8" smd rect
			(at -0.750062 1.875028 180)
			(size 0.254 0.5588)
			(layers "F.Cu" "F.Mask" "F.Paste")
			(net "SMB_HOST_CLK_GEN2_3V3AUX_SCL")
		)
		(pad "9" smd rect
			(at -0.249936 1.875028 180)
			(size 0.254 0.5588)
			(layers "F.Cu" "F.Mask" "F.Paste")
			(net "SMB_HOST_CLK_GEN2_3V3AUX_SDA")
		)
		(pad "10" smd rect
			(at 0.249936 1.875028 180)
			(size 0.254 0.5588)
			(layers "F.Cu" "F.Mask" "F.Paste")
			(net "GND")
		)
		(pad "11" smd rect
			(at 0.750062 1.875028 180)
			(size 0.254 0.5588)
			(layers "F.Cu" "F.Mask" "F.Paste")
			(net "VFG3P3_CLK_GEN")
		)
		(pad "12" smd rect
			(at 1.249934 1.875028 180)
			(size 0.254 0.5588)
			(layers "F.Cu" "F.Mask" "F.Paste")
			(net "CLK_GEN2_BMC_RC_OE_R3_N")
		)
		(pad "13" smd rect
			(at 1.875028 1.249934 90)
			(size 0.254 0.5588)
			(layers "F.Cu" "F.Mask" "F.Paste")
			(net "CLK_100M_BMC_RC_DP_R")
		)
		(pad "14" smd rect
			(at 1.875028 0.750062 90)
			(size 0.254 0.5588)
			(layers "F.Cu" "F.Mask" "F.Paste")
			(net "CLK_100M_BMC_RC_DN_R")
		)
		(pad "15" smd rect
			(at 1.875028 0.249936 90)
			(size 0.254 0.5588)
			(layers "F.Cu" "F.Mask" "F.Paste")
			(net "GND")
		)
		(pad "16" smd rect
			(at 1.875028 -0.249936 90)
			(size 0.254 0.5588)
			(layers "F.Cu" "F.Mask" "F.Paste")
			(net "VFG_3P3A_CLK_GEN")
		)
		(pad "17" smd rect
			(at 1.875028 -0.750062 90)
			(size 0.254 0.5588)
			(layers "F.Cu" "F.Mask" "F.Paste")
			(net "CLK_100M_GPU_FPGA_DP_R")
		)
		(pad "18" smd rect
			(at 1.875028 -1.249934 90)
			(size 0.254 0.5588)
			(layers "F.Cu" "F.Mask" "F.Paste")
			(net "CLK_100M_GPU_FPGA_DN_R")
		)
		(pad "19" smd rect
			(at 1.249934 -1.875028 180)
			(size 0.254 0.5588)
			(layers "F.Cu" "F.Mask" "F.Paste")
			(net "CLK_GEN2_GPU_OE_N")
		)
		(pad "20" smd rect
			(at 0.750062 -1.875028 180)
			(size 0.254 0.5588)
			(layers "F.Cu" "F.Mask" "F.Paste")
			(net "VFG3P3_CLK_GEN")
		)
		(pad "21" smd rect
			(at 0.249936 -1.875028 180)
			(size 0.254 0.5588)
			(layers "F.Cu" "F.Mask" "F.Paste")
			(net "GND")
		)
		(pad "22" smd rect
			(at -0.249936 -1.875028 180)
			(size 0.254 0.5588)
			(layers "F.Cu" "F.Mask" "F.Paste")
			(net "P3V3_PWRGD_CLKGEN")
		)
		(pad "23" smd rect
			(at -0.750062 -1.875028 180)
			(size 0.254 0.5588)
			(layers "F.Cu" "F.Mask" "F.Paste")
			(net "FG_SS_EN")
		)
		(pad "24" smd rect
			(at -1.249934 -1.875028 180)
			(size 0.254 0.5588)
			(layers "F.Cu" "F.Mask" "F.Paste")
			(net "GND")
		)
		(pad "25" smd circle
			(at 0 0 180)
			(size 0 0)
			(layers "F.Cu" "F.Mask" "F.Paste")
			(net "GND")
		)
	)
)
